(kicad_pcb
	(version 20260206)
	(generator "pcbnew")
	(generator_version "10.0")
	(general
		(thickness 1.6)
		(legacy_teardrops no)
	)
	(paper "A4")
	(title_block
		(title "01162023_DA0F0TEBIF0_F0T_Expander_BD_F_brd_V02_OCP.brd")
		(comment 1 "Grand Teton / footprints 7680-7687 of 9728")
	)
	(layers
		(0 "F.Cu" signal "TOP")
		(4 "In1.Cu" signal "GND")
		(6 "In2.Cu" signal "VCC")
		(8 "In3.Cu" signal "VCC1")
		(10 "In4.Cu" signal "GND1")
		(12 "In5.Cu" signal "IN1")
		(14 "In6.Cu" signal "GND2")
		(16 "In7.Cu" signal "IN2")
		(18 "In8.Cu" signal "GND3")
		(20 "In9.Cu" signal "IN3")
		(22 "In10.Cu" signal "GND4")
		(24 "In11.Cu" signal "IN4")
		(26 "In12.Cu" signal "GND5")
		(28 "In13.Cu" signal "IN5")
		(30 "In14.Cu" signal "GND6")
		(32 "In15.Cu" signal "IN6")
		(34 "In16.Cu" signal "GND7")
		(2 "B.Cu" signal "BOTTOM")
		(9 "F.Adhes" user "F.Adhesive")
		(11 "B.Adhes" user "B.Adhesive")
		(13 "F.Paste" user "Package Geometry/Pastemask Top")
		(15 "B.Paste" user "Package Geometry/Pastemask Bottom")
		(5 "F.SilkS" user "Ref Des/Silkscreen Top")
		(7 "B.SilkS" user "Ref Des/Silkscreen Bottom")
		(1 "F.Mask" user "Board Geometry/Soldermask Top")
		(3 "B.Mask" user "Board Geometry/Soldermask Bottom")
		(17 "Dwgs.User" user "User.Drawings")
		(19 "Cmts.User" user "User.Comments")
		(21 "Eco1.User" user "User.Eco1")
		(23 "Eco2.User" user "User.Eco2")
		(25 "Edge.Cuts" user "Board Geometry/Outline")
		(27 "Margin" user)
		(31 "F.CrtYd" user "Package Geometry/Place Bound Top")
		(29 "B.CrtYd" user "Package Geometry/Place Bound Bottom")
		(35 "F.Fab" user "Ref Des/Assembly Top")
		(33 "B.Fab" user "Ref Des/Assembly Bottom")
	)
	(footprint ""
		(layer "B.Cu")
		(at 348.750128 -326.934322 -90)
		(property "Reference" "C4313"
			(at 0 0 90)
			(layer "B.SilkS")
			(hide yes)
			(effects
				(font
					(size 1.27 1.27)
				)
				(justify mirror)
			)
		)
		(property "Value" ""
			(at 0 0 90)
			(layer "B.Fab")
			(effects
				(font
					(size 1.27 1.27)
				)
				(justify mirror)
			)
		)
		(duplicate_pad_numbers_are_jumpers no)
		(fp_line
			(start -1.2954 0.5842)
			(end 1.2954 0.5842)
			(stroke
				(width 0.1524)
				(type default)
			)
			(layer "B.SilkS")
		)
		(fp_line
			(start 1.2954 0.5842)
			(end 1.2954 -0.5842)
			(stroke
				(width 0.1524)
				(type default)
			)
			(layer "B.SilkS")
		)
		(fp_line
			(start -1.2954 -0.5842)
			(end -1.2954 0.5842)
			(stroke
				(width 0.1524)
				(type default)
			)
			(layer "B.SilkS")
		)
		(fp_line
			(start 1.2954 -0.5842)
			(end -1.2954 -0.5842)
			(stroke
				(width 0.1524)
				(type default)
			)
			(layer "B.SilkS")
		)
		(fp_line
			(start -0.8636 0.4572)
			(end 0.8636 0.4572)
			(stroke
				(width 0.1)
				(type default)
			)
			(layer "B.Fab")
		)
		(fp_line
			(start 0.8636 0.4572)
			(end 0.8636 0.4064)
			(stroke
				(width 0.1)
				(type default)
			)
			(layer "B.Fab")
		)
		(fp_line
			(start -1.1938 0.4064)
			(end -0.8636 0.4064)
			(stroke
				(width 0.1)
				(type default)
			)
			(layer "B.Fab")
		)
		(fp_line
			(start -0.8636 0.4064)
			(end -0.8636 0.4572)
			(stroke
				(width 0.1)
				(type default)
			)
			(layer "B.Fab")
		)
		(fp_line
			(start 0.8636 0.4064)
			(end 1.1938 0.4064)
			(stroke
				(width 0.1)
				(type default)
			)
			(layer "B.Fab")
		)
		(fp_line
			(start 1.1938 0.4064)
			(end 1.1938 -0.4064)
			(stroke
				(width 0.1)
				(type default)
			)
			(layer "B.Fab")
		)
		(fp_line
			(start -1.1938 -0.4064)
			(end -1.1938 0.4064)
			(stroke
				(width 0.1)
				(type default)
			)
			(layer "B.Fab")
		)
		(fp_line
			(start -0.8636 -0.4064)
			(end -1.1938 -0.4064)
			(stroke
				(width 0.1)
				(type default)
			)
			(layer "B.Fab")
		)
		(fp_line
			(start 0.8636 -0.4064)
			(end 0.8636 -0.4572)
			(stroke
				(width 0.1)
				(type default)
			)
			(layer "B.Fab")
		)
		(fp_line
			(start 1.1938 -0.4064)
			(end 0.8636 -0.4064)
			(stroke
				(width 0.1)
				(type default)
			)
			(layer "B.Fab")
		)
		(fp_line
			(start -0.8636 -0.4572)
			(end -0.8636 -0.4064)
			(stroke
				(width 0.1)
				(type default)
			)
			(layer "B.Fab")
		)
		(fp_line
			(start 0.8636 -0.4572)
			(end -0.8636 -0.4572)
			(stroke
				(width 0.1)
				(type default)
			)
			(layer "B.Fab")
		)
		(pad "1" smd rect
			(at 0.7366 0 180)
			(size 0.7112 0.8128)
			(layers "B.Cu" "B.Mask" "B.Paste")
			(net "P0V8_SERDES_VDDA_PEX2_C3")
		)
		(pad "2" smd rect
			(at -0.7366 0 180)
			(size 0.7112 0.8128)
			(layers "B.Cu" "B.Mask" "B.Paste")
			(net "GND")
		)
	)
	(footprint ""
		(layer "B.Cu")
		(at 406.402032 -376.492262 90)
		(property "Reference" "R6277"
			(at 0 0 90)
			(layer "B.SilkS")
			(hide yes)
			(effects
				(font
					(size 1.27 1.27)
				)
				(justify mirror)
			)
		)
		(property "Value" ""
			(at 0 0 90)
			(layer "B.Fab")
			(effects
				(font
					(size 1.27 1.27)
				)
				(justify mirror)
			)
		)
		(duplicate_pad_numbers_are_jumpers no)
		(fp_line
			(start 0.7874 -0.4064)
			(end -0.7874 -0.4064)
			(stroke
				(width 0.1524)
				(type default)
			)
			(layer "B.SilkS")
		)
		(fp_line
			(start -0.7874 -0.4064)
			(end -0.7874 0.4064)
			(stroke
				(width 0.1524)
				(type default)
			)
			(layer "B.SilkS")
		)
		(fp_line
			(start 0.7874 0.4064)
			(end 0.7874 -0.4064)
			(stroke
				(width 0.1524)
				(type default)
			)
			(layer "B.SilkS")
		)
		(fp_line
			(start -0.7874 0.4064)
			(end 0.7874 0.4064)
			(stroke
				(width 0.1524)
				(type default)
			)
			(layer "B.SilkS")
		)
		(fp_line
			(start 0.67945 -0.305054)
			(end 0.12065 -0.305054)
			(stroke
				(width 0.1)
				(type default)
			)
			(layer "B.Fab")
		)
		(fp_line
			(start 0.12065 -0.305054)
			(end 0.12065 -0.2794)
			(stroke
				(width 0.1)
				(type default)
			)
			(layer "B.Fab")
		)
		(fp_line
			(start -0.12065 -0.3048)
			(end -0.67945 -0.3048)
			(stroke
				(width 0.1)
				(type default)
			)
			(layer "B.Fab")
		)
		(fp_line
			(start -0.67945 -0.3048)
			(end -0.67945 0.3048)
			(stroke
				(width 0.1)
				(type default)
			)
			(layer "B.Fab")
		)
		(fp_line
			(start 0.12065 -0.2794)
			(end -0.12065 -0.2794)
			(stroke
				(width 0.1)
				(type default)
			)
			(layer "B.Fab")
		)
		(fp_line
			(start -0.12065 -0.2794)
			(end -0.12065 -0.3048)
			(stroke
				(width 0.1)
				(type default)
			)
			(layer "B.Fab")
		)
		(fp_line
			(start 0.12065 0.2794)
			(end 0.12065 0.3048)
			(stroke
				(width 0.1)
				(type default)
			)
			(layer "B.Fab")
		)
		(fp_line
			(start -0.120396 0.2794)
			(end 0.12065 0.2794)
			(stroke
				(width 0.1)
				(type default)
			)
			(layer "B.Fab")
		)
		(fp_line
			(start 0.67945 0.3048)
			(end 0.67945 -0.305054)
			(stroke
				(width 0.1)
				(type default)
			)
			(layer "B.Fab")
		)
		(fp_line
			(start 0.12065 0.3048)
			(end 0.67945 0.3048)
			(stroke
				(width 0.1)
				(type default)
			)
			(layer "B.Fab")
		)
		(fp_line
			(start -0.120396 0.3048)
			(end -0.120396 0.2794)
			(stroke
				(width 0.1)
				(type default)
			)
			(layer "B.Fab")
		)
		(fp_line
			(start -0.67945 0.3048)
			(end -0.120396 0.3048)
			(stroke
				(width 0.1)
				(type default)
			)
			(layer "B.Fab")
		)
		(pad "1" smd circle
			(at 0.40005 0 270)
			(size 0 0)
			(layers "B.Cu" "B.Mask" "B.Paste")
			(net "I3C_MB_BMC_R_SDA")
		)
		(pad "2" smd circle
			(at -0.40005 0 270)
			(size 0 0)
			(layers "B.Cu" "B.Mask" "B.Paste")
			(net "SMB_MB_I3C_ISO_SDA")
		)
	)
	(footprint ""
		(layer "B.Cu")
		(at 295.649904 -288.299906 90)
		(property "Reference" "C3276"
			(at 0 0 90)
			(layer "B.SilkS")
			(hide yes)
			(effects
				(font
					(size 1.27 1.27)
				)
				(justify mirror)
			)
		)
		(property "Value" ""
			(at 0 0 90)
			(layer "B.Fab")
			(effects
				(font
					(size 1.27 1.27)
				)
				(justify mirror)
			)
		)
		(duplicate_pad_numbers_are_jumpers no)
		(fp_line
			(start 0.299974 -0.150114)
			(end -0.299974 -0.150114)
			(stroke
				(width 0.1)
				(type default)
			)
			(layer "B.Fab")
		)
		(fp_line
			(start -0.299974 -0.150114)
			(end -0.299974 0.150114)
			(stroke
				(width 0.1)
				(type default)
			)
			(layer "B.Fab")
		)
		(fp_line
			(start 0.299974 0.150114)
			(end 0.299974 -0.150114)
			(stroke
				(width 0.1)
				(type default)
			)
			(layer "B.Fab")
		)
		(fp_line
			(start -0.299974 0.150114)
			(end 0.299974 0.150114)
			(stroke
				(width 0.1)
				(type default)
			)
			(layer "B.Fab")
		)
		(pad "1" smd rect
			(at 0.2667 0 270)
			(size 0.3048 0.381)
			(layers "B.Cu" "B.Mask" "B.Paste")
			(net "P1V25_PEX2")
		)
		(pad "2" smd rect
			(at -0.2667 0 270)
			(size 0.3048 0.381)
			(layers "B.Cu" "B.Mask" "B.Paste")
			(net "GND")
		)
	)
	(footprint ""
		(layer "B.Cu")
		(at 285.199836 -301.599854 -90)
		(property "Reference" "C1687"
			(at 0 0 90)
			(layer "B.SilkS")
			(hide yes)
			(effects
				(font
					(size 1.27 1.27)
				)
				(justify mirror)
			)
		)
		(property "Value" ""
			(at 0 0 90)
			(layer "B.Fab")
			(effects
				(font
					(size 1.27 1.27)
				)
				(justify mirror)
			)
		)
		(duplicate_pad_numbers_are_jumpers no)
		(fp_line
			(start -0.299974 0.150114)
			(end 0.299974 0.150114)
			(stroke
				(width 0.1)
				(type default)
			)
			(layer "B.Fab")
		)
		(fp_line
			(start 0.299974 0.150114)
			(end 0.299974 -0.150114)
			(stroke
				(width 0.1)
				(type default)
			)
			(layer "B.Fab")
		)
		(fp_line
			(start -0.299974 -0.150114)
			(end -0.299974 0.150114)
			(stroke
				(width 0.1)
				(type default)
			)
			(layer "B.Fab")
		)
		(fp_line
			(start 0.299974 -0.150114)
			(end -0.299974 -0.150114)
			(stroke
				(width 0.1)
				(type default)
			)
			(layer "B.Fab")
		)
		(pad "1" smd rect
			(at 0.2667 0 90)
			(size 0.3048 0.381)
			(layers "B.Cu" "B.Mask" "B.Paste")
			(net "P0V8_SERDES_VDDA_PEX2")
		)
		(pad "2" smd rect
			(at -0.2667 0 90)
			(size 0.3048 0.381)
			(layers "B.Cu" "B.Mask" "B.Paste")
			(net "GND")
		)
	)
	(footprint ""
		(layer "B.Cu")
		(at 188.308234 -300.174914 180)
		(property "Reference" "C3164"
			(at 0 0 0)
			(layer "B.SilkS")
			(hide yes)
			(effects
				(font
					(size 1.27 1.27)
				)
				(justify mirror)
			)
		)
		(property "Value" ""
			(at 0 0 0)
			(layer "B.Fab")
			(effects
				(font
					(size 1.27 1.27)
				)
				(justify mirror)
			)
		)
		(duplicate_pad_numbers_are_jumpers no)
		(fp_line
			(start 0.299974 0.150114)
			(end 0.299974 -0.150114)
			(stroke
				(width 0.1)
				(type default)
			)
			(layer "B.Fab")
		)
		(fp_line
			(start 0.299974 -0.150114)
			(end -0.299974 -0.150114)
			(stroke
				(width 0.1)
				(type default)
			)
			(layer "B.Fab")
		)
		(fp_line
			(start -0.299974 0.150114)
			(end 0.299974 0.150114)
			(stroke
				(width 0.1)
				(type default)
			)
			(layer "B.Fab")
		)
		(fp_line
			(start -0.299974 -0.150114)
			(end -0.299974 0.150114)
			(stroke
				(width 0.1)
				(type default)
			)
			(layer "B.Fab")
		)
		(pad "1" smd rect
			(at 0.2667 0)
			(size 0.3048 0.381)
			(layers "B.Cu" "B.Mask" "B.Paste")
			(net "P1V8_VDDA_PEX1")
		)
		(pad "2" smd rect
			(at -0.2667 0)
			(size 0.3048 0.381)
			(layers "B.Cu" "B.Mask" "B.Paste")
			(net "GND")
		)
	)
	(footprint ""
		(layer "B.Cu")
		(at 232.823512 -234.728004 90)
		(property "Reference" "R6186"
			(at 0 0 90)
			(layer "B.SilkS")
			(hide yes)
			(effects
				(font
					(size 1.27 1.27)
				)
				(justify mirror)
			)
		)
		(property "Value" ""
			(at 0 0 90)
			(layer "B.Fab")
			(effects
				(font
					(size 1.27 1.27)
				)
				(justify mirror)
			)
		)
		(duplicate_pad_numbers_are_jumpers no)
		(fp_line
			(start 0.7874 -0.4064)
			(end -0.7874 -0.4064)
			(stroke
				(width 0.1524)
				(type default)
			)
			(layer "B.SilkS")
		)
		(fp_line
			(start -0.7874 -0.4064)
			(end -0.7874 0.4064)
			(stroke
				(width 0.1524)
				(type default)
			)
			(layer "B.SilkS")
		)
		(fp_line
			(start 0.7874 0.4064)
			(end 0.7874 -0.4064)
			(stroke
				(width 0.1524)
				(type default)
			)
			(layer "B.SilkS")
		)
		(fp_line
			(start -0.7874 0.4064)
			(end 0.7874 0.4064)
			(stroke
				(width 0.1524)
				(type default)
			)
			(layer "B.SilkS")
		)
		(fp_line
			(start 0.67945 -0.305054)
			(end 0.12065 -0.305054)
			(stroke
				(width 0.1)
				(type default)
			)
			(layer "B.Fab")
		)
		(fp_line
			(start 0.12065 -0.305054)
			(end 0.12065 -0.2794)
			(stroke
				(width 0.1)
				(type default)
			)
			(layer "B.Fab")
		)
		(fp_line
			(start -0.12065 -0.3048)
			(end -0.67945 -0.3048)
			(stroke
				(width 0.1)
				(type default)
			)
			(layer "B.Fab")
		)
		(fp_line
			(start -0.67945 -0.3048)
			(end -0.67945 0.3048)
			(stroke
				(width 0.1)
				(type default)
			)
			(layer "B.Fab")
		)
		(fp_line
			(start 0.12065 -0.2794)
			(end -0.12065 -0.2794)
			(stroke
				(width 0.1)
				(type default)
			)
			(layer "B.Fab")
		)
		(fp_line
			(start -0.12065 -0.2794)
			(end -0.12065 -0.3048)
			(stroke
				(width 0.1)
				(type default)
			)
			(layer "B.Fab")
		)
		(fp_line
			(start 0.12065 0.2794)
			(end 0.12065 0.3048)
			(stroke
				(width 0.1)
				(type default)
			)
			(layer "B.Fab")
		)
		(fp_line
			(start -0.120396 0.2794)
			(end 0.12065 0.2794)
			(stroke
				(width 0.1)
				(type default)
			)
			(layer "B.Fab")
		)
		(fp_line
			(start 0.67945 0.3048)
			(end 0.67945 -0.305054)
			(stroke
				(width 0.1)
				(type default)
			)
			(layer "B.Fab")
		)
		(fp_line
			(start 0.12065 0.3048)
			(end 0.67945 0.3048)
			(stroke
				(width 0.1)
				(type default)
			)
			(layer "B.Fab")
		)
		(fp_line
			(start -0.120396 0.3048)
			(end -0.120396 0.2794)
			(stroke
				(width 0.1)
				(type default)
			)
			(layer "B.Fab")
		)
		(fp_line
			(start -0.67945 0.3048)
			(end -0.120396 0.3048)
			(stroke
				(width 0.1)
				(type default)
			)
			(layer "B.Fab")
		)
		(pad "1" smd circle
			(at 0.40005 0 270)
			(size 0 0)
			(layers "B.Cu" "B.Mask" "B.Paste")
			(net "GND")
		)
		(pad "2" smd circle
			(at -0.40005 0 270)
			(size 0 0)
			(layers "B.Cu" "B.Mask" "B.Paste")
			(net "SSD4_PWRDIS_BIC_R")
		)
	)
	(footprint ""
		(layer "B.Cu")
		(at 29.741622 -226.78263 180)
		(property "Reference" "R6162"
			(at 0 0 0)
			(layer "B.SilkS")
			(hide yes)
			(effects
				(font
					(size 1.27 1.27)
				)
				(justify mirror)
			)
		)
		(property "Value" ""
			(at 0 0 0)
			(layer "B.Fab")
			(effects
				(font
					(size 1.27 1.27)
				)
				(justify mirror)
			)
		)
		(duplicate_pad_numbers_are_jumpers no)
		(fp_line
			(start 0.7874 0.4064)
			(end 0.7874 -0.4064)
			(stroke
				(width 0.1524)
				(type default)
			)
			(layer "B.SilkS")
		)
		(fp_line
			(start 0.7874 -0.4064)
			(end -0.7874 -0.4064)
			(stroke
				(width 0.1524)
				(type default)
			)
			(layer "B.SilkS")
		)
		(fp_line
			(start -0.7874 0.4064)
			(end 0.7874 0.4064)
			(stroke
				(width 0.1524)
				(type default)
			)
			(layer "B.SilkS")
		)
		(fp_line
			(start -0.7874 -0.4064)
			(end -0.7874 0.4064)
			(stroke
				(width 0.1524)
				(type default)
			)
			(layer "B.SilkS")
		)
		(fp_line
			(start 0.67945 0.3048)
			(end 0.67945 -0.305054)
			(stroke
				(width 0.1)
				(type default)
			)
			(layer "B.Fab")
		)
		(fp_line
			(start 0.67945 -0.305054)
			(end 0.12065 -0.305054)
			(stroke
				(width 0.1)
				(type default)
			)
			(layer "B.Fab")
		)
		(fp_line
			(start 0.12065 0.3048)
			(end 0.67945 0.3048)
			(stroke
				(width 0.1)
				(type default)
			)
			(layer "B.Fab")
		)
		(fp_line
			(start 0.12065 0.2794)
			(end 0.12065 0.3048)
			(stroke
				(width 0.1)
				(type default)
			)
			(layer "B.Fab")
		)
		(fp_line
			(start 0.12065 -0.2794)
			(end -0.12065 -0.2794)
			(stroke
				(width 0.1)
				(type default)
			)
			(layer "B.Fab")
		)
		(fp_line
			(start 0.12065 -0.305054)
			(end 0.12065 -0.2794)
			(stroke
				(width 0.1)
				(type default)
			)
			(layer "B.Fab")
		)
		(fp_line
			(start -0.120396 0.3048)
			(end -0.120396 0.2794)
			(stroke
				(width 0.1)
				(type default)
			)
			(layer "B.Fab")
		)
		(fp_line
			(start -0.120396 0.2794)
			(end 0.12065 0.2794)
			(stroke
				(width 0.1)
				(type default)
			)
			(layer "B.Fab")
		)
		(fp_line
			(start -0.12065 -0.2794)
			(end -0.12065 -0.3048)
			(stroke
				(width 0.1)
				(type default)
			)
			(layer "B.Fab")
		)
		(fp_line
			(start -0.12065 -0.3048)
			(end -0.67945 -0.3048)
			(stroke
				(width 0.1)
				(type default)
			)
			(layer "B.Fab")
		)
		(fp_line
			(start -0.67945 0.3048)
			(end -0.120396 0.3048)
			(stroke
				(width 0.1)
				(type default)
			)
			(layer "B.Fab")
		)
		(fp_line
			(start -0.67945 -0.3048)
			(end -0.67945 0.3048)
			(stroke
				(width 0.1)
				(type default)
			)
			(layer "B.Fab")
		)
		(pad "1" smd circle
			(at 0.40005 0)
			(size 0 0)
			(layers "B.Cu" "B.Mask" "B.Paste")
			(net "SPI_PEX0_RST_R_N")
		)
		(pad "2" smd circle
			(at -0.40005 0)
			(size 0 0)
			(layers "B.Cu" "B.Mask" "B.Paste")
			(net "SPI_PEX0_RST_N")
		)
	)
	(footprint ""
		(layer "B.Cu")
		(at 298.276518 -111.334042 180)
		(property "Reference" "R291"
			(at 0 0 0)
			(layer "B.SilkS")
			(hide yes)
			(effects
				(font
					(size 1.27 1.27)
				)
				(justify mirror)
			)
		)
		(property "Value" ""
			(at 0 0 0)
			(layer "B.Fab")
			(effects
				(font
					(size 1.27 1.27)
				)
				(justify mirror)
			)
		)
		(duplicate_pad_numbers_are_jumpers no)
		(fp_line
			(start 0.7874 0.4064)
			(end 0.7874 -0.4064)
			(stroke
				(width 0.1524)
				(type default)
			)
			(layer "B.SilkS")
		)
		(fp_line
			(start 0.7874 -0.4064)
			(end -0.7874 -0.4064)
			(stroke
				(width 0.1524)
				(type default)
			)
			(layer "B.SilkS")
		)
		(fp_line
			(start -0.7874 0.4064)
			(end 0.7874 0.4064)
			(stroke
				(width 0.1524)
				(type default)
			)
			(layer "B.SilkS")
		)
		(fp_line
			(start -0.7874 -0.4064)
			(end -0.7874 0.4064)
			(stroke
				(width 0.1524)
				(type default)
			)
			(layer "B.SilkS")
		)
		(fp_line
			(start 0.67945 0.3048)
			(end 0.67945 -0.305054)
			(stroke
				(width 0.1)
				(type default)
			)
			(layer "B.Fab")
		)
		(fp_line
			(start 0.67945 -0.305054)
			(end 0.12065 -0.305054)
			(stroke
				(width 0.1)
				(type default)
			)
			(layer "B.Fab")
		)
		(fp_line
			(start 0.12065 0.3048)
			(end 0.67945 0.3048)
			(stroke
				(width 0.1)
				(type default)
			)
			(layer "B.Fab")
		)
		(fp_line
			(start 0.12065 0.2794)
			(end 0.12065 0.3048)
			(stroke
				(width 0.1)
				(type default)
			)
			(layer "B.Fab")
		)
		(fp_line
			(start 0.12065 -0.2794)
			(end -0.12065 -0.2794)
			(stroke
				(width 0.1)
				(type default)
			)
			(layer "B.Fab")
		)
		(fp_line
			(start 0.12065 -0.305054)
			(end 0.12065 -0.2794)
			(stroke
				(width 0.1)
				(type default)
			)
			(layer "B.Fab")
		)
		(fp_line
			(start -0.120396 0.3048)
			(end -0.120396 0.2794)
			(stroke
				(width 0.1)
				(type default)
			)
			(layer "B.Fab")
		)
		(fp_line
			(start -0.120396 0.2794)
			(end 0.12065 0.2794)
			(stroke
				(width 0.1)
				(type default)
			)
			(layer "B.Fab")
		)
		(fp_line
			(start -0.12065 -0.2794)
			(end -0.12065 -0.3048)
			(stroke
				(width 0.1)
				(type default)
			)
			(layer "B.Fab")
		)
		(fp_line
			(start -0.12065 -0.3048)
			(end -0.67945 -0.3048)
			(stroke
				(width 0.1)
				(type default)
			)
			(layer "B.Fab")
		)
		(fp_line
			(start -0.67945 0.3048)
			(end -0.120396 0.3048)
			(stroke
				(width 0.1)
				(type default)
			)
			(layer "B.Fab")
		)
		(fp_line
			(start -0.67945 -0.3048)
			(end -0.67945 0.3048)
			(stroke
				(width 0.1)
				(type default)
			)
			(layer "B.Fab")
		)
		(pad "1" smd circle
			(at 0.40005 0)
			(size 0 0)
			(layers "B.Cu" "B.Mask" "B.Paste")
			(net "RST_SMB_NIC_MUX_R_N")
		)
		(pad "2" smd circle
			(at -0.40005 0)
			(size 0 0)
			(layers "B.Cu" "B.Mask" "B.Paste")
			(net "RST_SMB_NIC5_MUX_N")
		)
	)
)
